# S9S_MB_2U (Grand Teton) — schematic netlist excerpt (pin names and nets, part order shuffled) for the footprints in the layout excerpt that follows; sources: Cadence DE-HDL packaged netlist, KiCad conversion of 03242023_DA0F0TMBIJ0_F0T_Motherboard_J_brd_V01_OCP.brd

PC523  Q_CAP  2.2UF 10V 10% X6S  pkg C0402  page 286 : A = PVCCIN_CPU1_VDD4 ; B = GND
C1101  Q_CAP_DIFFBUS  DIFF BUS_0.22UF 6.3V 20% X6S  pkg C0201  page 181 : \1\ = P3E_PCH_M2_TX_DN<2> ; \2\ = P3E_PCH_M2_TX_C_DN<2>
R4641  Q_RES  243 1% CHIP  pkg 1206LF  page 260 : A = P5V ; B = VR_P5V_EN_D

(kicad_pcb
	(version 20260206)
	(generator "pcbnew")
	(generator_version "10.0")
	(general
		(thickness 1.6)
		(legacy_teardrops no)
	)
	(paper "A4")
	(title_block
		(title "03242023_DA0F0TMBIJ0_F0T_Motherboard_J_brd_V01_OCP.brd")
		(comment 1 "Grand Teton / footprints 1973-1975 of 6105")
	)
	(layers
		(0 "F.Cu" signal "TOP")
		(4 "In1.Cu" signal "GND")
		(6 "In2.Cu" signal "IN1")
		(8 "In3.Cu" signal "GND1")
		(10 "In4.Cu" signal "IN2")
		(12 "In5.Cu" signal "GND2")
		(14 "In6.Cu" signal "IN3")
		(16 "In7.Cu" signal "GND3")
		(18 "In8.Cu" signal "VCC")
		(20 "In9.Cu" signal "VCC1")
		(22 "In10.Cu" signal "GND4")
		(24 "In11.Cu" signal "IN4")
		(26 "In12.Cu" signal "GND5")
		(28 "In13.Cu" signal "IN5")
		(30 "In14.Cu" signal "GND6")
		(32 "In15.Cu" signal "IN6")
		(34 "In16.Cu" signal "GND7")
		(2 "B.Cu" signal "BOTTOM")
		(9 "F.Adhes" user "F.Adhesive")
		(11 "B.Adhes" user "B.Adhesive")
		(13 "F.Paste" user "Package Geometry/Pastemask Top")
		(15 "B.Paste" user "Package Geometry/Pastemask Bottom")
		(5 "F.SilkS" user "Ref Des/Silkscreen Top")
		(7 "B.SilkS" user "Ref Des/Silkscreen Bottom")
		(1 "F.Mask" user "Board Geometry/Soldermask Top")
		(3 "B.Mask" user "Board Geometry/Soldermask Bottom")
		(17 "Dwgs.User" user "User.Drawings")
		(19 "Cmts.User" user "User.Comments")
		(21 "Eco1.User" user "User.Eco1")
		(23 "Eco2.User" user "User.Eco2")
		(25 "Edge.Cuts" user "Board Geometry/Outline")
		(27 "Margin" user)
		(31 "F.CrtYd" user "Package Geometry/Place Bound Top")
		(29 "B.CrtYd" user "Package Geometry/Place Bound Bottom")
		(35 "F.Fab" user "Ref Des/Assembly Top")
		(33 "B.Fab" user "Ref Des/Assembly Bottom")
	)
	(footprint ""
		(layer "F.Cu")
		(at 117.904514 -336.192368 90)
		(property "Reference" "PC523"
			(at 0 0 90)
			(layer "F.SilkS")
			(hide yes)
			(effects
				(font
					(size 1.27 1.27)
				)
			)
		)
		(property "Value" ""
			(at 0 0 90)
			(layer "F.Fab")
			(effects
				(font
					(size 1.27 1.27)
				)
			)
		)
		(duplicate_pad_numbers_are_jumpers no)
		(fp_line
			(start 0.7874 -0.4064)
			(end 0.7874 0.4064)
			(stroke
				(width 0.1524)
				(type default)
			)
			(layer "F.SilkS")
		)
		(fp_line
			(start -0.7874 -0.4064)
			(end 0.7874 -0.4064)
			(stroke
				(width 0.1524)
				(type default)
			)
			(layer "F.SilkS")
		)
		(fp_line
			(start 0.7874 0.4064)
			(end -0.7874 0.4064)
			(stroke
				(width 0.1524)
				(type default)
			)
			(layer "F.SilkS")
		)
		(fp_line
			(start -0.7874 0.4064)
			(end -0.7874 -0.4064)
			(stroke
				(width 0.1524)
				(type default)
			)
			(layer "F.SilkS")
		)
		(fp_line
			(start -0.12065 -0.305054)
			(end -0.12065 -0.2794)
			(stroke
				(width 0.1)
				(type default)
			)
			(layer "F.Fab")
		)
		(fp_line
			(start -0.67945 -0.305054)
			(end -0.12065 -0.305054)
			(stroke
				(width 0.1)
				(type default)
			)
			(layer "F.Fab")
		)
		(fp_line
			(start 0.67945 -0.3048)
			(end 0.67945 0.3048)
			(stroke
				(width 0.1)
				(type default)
			)
			(layer "F.Fab")
		)
		(fp_line
			(start 0.12065 -0.3048)
			(end 0.67945 -0.3048)
			(stroke
				(width 0.1)
				(type default)
			)
			(layer "F.Fab")
		)
		(fp_line
			(start 0.12065 -0.2794)
			(end 0.12065 -0.3048)
			(stroke
				(width 0.1)
				(type default)
			)
			(layer "F.Fab")
		)
		(fp_line
			(start -0.12065 -0.2794)
			(end 0.12065 -0.2794)
			(stroke
				(width 0.1)
				(type default)
			)
			(layer "F.Fab")
		)
		(fp_line
			(start 0.120396 0.2794)
			(end -0.12065 0.2794)
			(stroke
				(width 0.1)
				(type default)
			)
			(layer "F.Fab")
		)
		(fp_line
			(start -0.12065 0.2794)
			(end -0.12065 0.3048)
			(stroke
				(width 0.1)
				(type default)
			)
			(layer "F.Fab")
		)
		(fp_line
			(start 0.67945 0.3048)
			(end 0.120396 0.3048)
			(stroke
				(width 0.1)
				(type default)
			)
			(layer "F.Fab")
		)
		(fp_line
			(start 0.120396 0.3048)
			(end 0.120396 0.2794)
			(stroke
				(width 0.1)
				(type default)
			)
			(layer "F.Fab")
		)
		(fp_line
			(start -0.12065 0.3048)
			(end -0.67945 0.3048)
			(stroke
				(width 0.1)
				(type default)
			)
			(layer "F.Fab")
		)
		(fp_line
			(start -0.67945 0.3048)
			(end -0.67945 -0.305054)
			(stroke
				(width 0.1)
				(type default)
			)
			(layer "F.Fab")
		)
		(pad "1" smd circle
			(at -0.40005 0 90)
			(size 0 0)
			(layers "F.Cu" "F.Mask" "F.Paste")
			(net "PVCCIN_CPU1_VDD4")
		)
		(pad "2" smd circle
			(at 0.40005 0 90)
			(size 0 0)
			(layers "F.Cu" "F.Mask" "F.Paste")
			(net "GND")
		)
	)
	(footprint ""
		(layer "F.Cu")
		(at 180.528468 -47.139098 180)
		(property "Reference" "C1101"
			(at 0 0 180)
			(layer "F.SilkS")
			(hide yes)
			(effects
				(font
					(size 1.27 1.27)
				)
			)
		)
		(property "Value" ""
			(at 0 0 180)
			(layer "F.Fab")
			(effects
				(font
					(size 1.27 1.27)
				)
			)
		)
		(duplicate_pad_numbers_are_jumpers no)
		(fp_line
			(start 0.299974 0.150114)
			(end -0.299974 0.150114)
			(stroke
				(width 0.1)
				(type default)
			)
			(layer "F.Fab")
		)
		(fp_line
			(start 0.299974 -0.150114)
			(end 0.299974 0.150114)
			(stroke
				(width 0.1)
				(type default)
			)
			(layer "F.Fab")
		)
		(fp_line
			(start -0.299974 0.150114)
			(end -0.299974 -0.150114)
			(stroke
				(width 0.1)
				(type default)
			)
			(layer "F.Fab")
		)
		(fp_line
			(start -0.299974 -0.150114)
			(end 0.299974 -0.150114)
			(stroke
				(width 0.1)
				(type default)
			)
			(layer "F.Fab")
		)
		(pad "1" smd rect
			(at -0.2667 0 180)
			(size 0.3048 0.381)
			(layers "F.Cu" "F.Mask" "F.Paste")
			(net "P3E_PCH_M2_TX_DN<2>")
		)
		(pad "2" smd rect
			(at 0.2667 0 180)
			(size 0.3048 0.381)
			(layers "F.Cu" "F.Mask" "F.Paste")
			(net "P3E_PCH_M2_TX_C_DN<2>")
		)
		(zone
			(layer "In1.Cu")
			(hatch none 0.5)
			(connect_pads
				(clearance 0)
			)
			(min_thickness 0.25)
			(keepout
				(tracks not_allowed)
				(vias allowed)
				(pads allowed)
				(copperpour not_allowed)
				(footprints allowed)
			)
			(placement
				(enabled no)
				(sheetname "")
			)
			(fill
				(thermal_gap 0.5)
				(thermal_bridge_width 0.5)
				(island_removal_mode 0)
			)
			(polygon
				(pts
					(arc
						(start 180.388768 -47.380398)
						(mid 180.44265 -47.35808)
						(end 180.464968 -47.304198)
					)
					(arc
						(start 180.464968 -46.973998)
						(mid 180.44265 -46.920116)
						(end 180.388768 -46.897798)
					)
					(arc
						(start 180.134768 -46.897798)
						(mid 180.080886 -46.920116)
						(end 180.058568 -46.973998)
					)
					(arc
						(start 180.058568 -47.304198)
						(mid 180.080886 -47.35808)
						(end 180.134768 -47.380398)
					)
				)
			)
		)
		(zone
			(layer "In1.Cu")
			(hatch none 0.5)
			(connect_pads
				(clearance 0)
			)
			(min_thickness 0.25)
			(keepout
				(tracks not_allowed)
				(vias allowed)
				(pads allowed)
				(copperpour not_allowed)
				(footprints allowed)
			)
			(placement
				(enabled no)
				(sheetname "")
			)
			(fill
				(thermal_gap 0.5)
				(thermal_bridge_width 0.5)
				(island_removal_mode 0)
			)
			(polygon
				(pts
					(arc
						(start 180.922168 -47.380398)
						(mid 180.97605 -47.35808)
						(end 180.998368 -47.304198)
					)
					(arc
						(start 180.998368 -46.973998)
						(mid 180.97605 -46.920116)
						(end 180.922168 -46.897798)
					)
					(arc
						(start 180.668168 -46.897798)
						(mid 180.614286 -46.920116)
						(end 180.591968 -46.973998)
					)
					(arc
						(start 180.591968 -47.304198)
						(mid 180.614286 -47.35808)
						(end 180.668168 -47.380398)
					)
				)
			)
		)
	)
	(footprint ""
		(layer "F.Cu")
		(at 161.29 -126.365 -90)
		(property "Reference" "R4641"
			(at 0 0 270)
			(layer "F.SilkS")
			(hide yes)
			(effects
				(font
					(size 1.27 1.27)
				)
			)
		)
		(property "Value" ""
			(at 0 0 270)
			(layer "F.Fab")
			(effects
				(font
					(size 1.27 1.27)
				)
			)
		)
		(duplicate_pad_numbers_are_jumpers no)
		(fp_line
			(start -2.234946 0.9271)
			(end -2.234946 -0.9271)
			(stroke
				(width 0.1524)
				(type default)
			)
			(layer "F.SilkS")
		)
		(fp_line
			(start 2.234946 0.9271)
			(end -2.234946 0.9271)
			(stroke
				(width 0.1524)
				(type default)
			)
			(layer "F.SilkS")
		)
		(fp_line
			(start -2.234946 -0.9271)
			(end 2.234946 -0.9271)
			(stroke
				(width 0.1524)
				(type default)
			)
			(layer "F.SilkS")
		)
		(fp_line
			(start 2.234946 -0.9271)
			(end 2.234946 0.9271)
			(stroke
				(width 0.1524)
				(type default)
			)
			(layer "F.SilkS")
		)
		(fp_line
			(start -1.575054 0.824992)
			(end 1.575054 0.824992)
			(stroke
				(width 0.1)
				(type default)
			)
			(layer "F.Fab")
		)
		(fp_line
			(start 1.575054 0.824992)
			(end 1.575054 -0.824992)
			(stroke
				(width 0.1)
				(type default)
			)
			(layer "F.Fab")
		)
		(fp_line
			(start -1.575054 -0.824992)
			(end -1.575054 0.824992)
			(stroke
				(width 0.1)
				(type default)
			)
			(layer "F.Fab")
		)
		(fp_line
			(start 1.575054 -0.824992)
			(end -1.575054 -0.824992)
			(stroke
				(width 0.1)
				(type default)
			)
			(layer "F.Fab")
		)
		(pad "1" smd rect
			(at -1.599946 0 270)
			(size 1.016 1.6002)
			(layers "F.Cu" "F.Mask" "F.Paste")
			(net "P5V")
		)
		(pad "2" smd rect
			(at 1.599946 0 270)
			(size 1.016 1.6002)
			(layers "F.Cu" "F.Mask" "F.Paste")
			(net "VR_P5V_EN_D")
		)
	)
)
